# S9S_MB_2U (Grand Teton) — schematic netlist excerpt (pin names and nets, part order shuffled) for the footprints in the layout excerpt that follows; sources: Cadence DE-HDL packaged netlist, KiCad conversion of 03242023_DA0F0TMBIJ0_F0T_Motherboard_J_brd_V01_OCP.brd

U14  QS3VH257QG8  IC  pkg SMLF  page 230
  S  = FM_SPD_REMOTE_EN
  I0A  = I3C_SPD_DDRABCD_CPU1_R_SCL
  I1A  = I3C_SPD_DDRABCD_CPU1_BMC_SCL
  YA  = I3C_SPD_DDRABCD_CPU1_LVC1_R_SCL
  I0B  = I3C_SPD_DDRABCD_CPU1_R_SDA
  I1B  = I3C_SPD_DDRABCD_CPU1_BMC_SDA
  YB  = I3C_SPD_DDRABCD_CPU1_LVC1_R_SDA
  GND  = GND
  YC  = I3C_SPD_DDREFGH_CPU1_LVC1_R_SCL
  I1C  = I3C_SPD_DDREFGH_CPU1_BMC_SCL
  I0C  = I3C_SPD_DDREFGH_CPU1_R_SCL
  YD  = I3C_SPD_DDREFGH_CPU1_LVC1_R_SDA
  I1D  = I3C_SPD_DDREFGH_CPU1_BMC_SDA
  I0D  = I3C_SPD_DDREFGH_CPU1_R_SDA
  \e*\  = PD_I3C_SPD_DDR_CPU1_OE_N
  VCC  = P3V3_AUX

(kicad_pcb
	(version 20260206)
	(generator "pcbnew")
	(generator_version "10.0")
	(general
		(thickness 1.6)
		(legacy_teardrops no)
	)
	(paper "A4")
	(title_block
		(title "03242023_DA0F0TMBIJ0_F0T_Motherboard_J_brd_V01_OCP.brd")
		(comment 1 "Grand Teton / footprints 304-304 of 6105")
	)
	(layers
		(0 "F.Cu" signal "TOP")
		(4 "In1.Cu" signal "GND")
		(6 "In2.Cu" signal "IN1")
		(8 "In3.Cu" signal "GND1")
		(10 "In4.Cu" signal "IN2")
		(12 "In5.Cu" signal "GND2")
		(14 "In6.Cu" signal "IN3")
		(16 "In7.Cu" signal "GND3")
		(18 "In8.Cu" signal "VCC")
		(20 "In9.Cu" signal "VCC1")
		(22 "In10.Cu" signal "GND4")
		(24 "In11.Cu" signal "IN4")
		(26 "In12.Cu" signal "GND5")
		(28 "In13.Cu" signal "IN5")
		(30 "In14.Cu" signal "GND6")
		(32 "In15.Cu" signal "IN6")
		(34 "In16.Cu" signal "GND7")
		(2 "B.Cu" signal "BOTTOM")
		(9 "F.Adhes" user "F.Adhesive")
		(11 "B.Adhes" user "B.Adhesive")
		(13 "F.Paste" user "Package Geometry/Pastemask Top")
		(15 "B.Paste" user "Package Geometry/Pastemask Bottom")
		(5 "F.SilkS" user "Ref Des/Silkscreen Top")
		(7 "B.SilkS" user "Ref Des/Silkscreen Bottom")
		(1 "F.Mask" user "Board Geometry/Soldermask Top")
		(3 "B.Mask" user "Board Geometry/Soldermask Bottom")
		(17 "Dwgs.User" user "User.Drawings")
		(19 "Cmts.User" user "User.Comments")
		(21 "Eco1.User" user "User.Eco1")
		(23 "Eco2.User" user "User.Eco2")
		(25 "Edge.Cuts" user "Board Geometry/Outline")
		(27 "Margin" user)
		(31 "F.CrtYd" user "Package Geometry/Place Bound Top")
		(29 "B.CrtYd" user "Package Geometry/Place Bound Bottom")
		(35 "F.Fab" user "Ref Des/Assembly Top")
		(33 "B.Fab" user "Ref Des/Assembly Bottom")
	)
	(footprint ""
		(layer "F.Cu")
		(at 79.691738 -147.677632)
		(property "Reference" "U14"
			(at 3.05308 3.23469 0)
			(unlocked yes)
			(layer "F.SilkS")
			(effects
				(font
					(size 0.7874 0.5842)
					(thickness 0.1524)
				)
				(justify left)
			)
		)
		(property "Value" ""
			(at 0 0 0)
			(layer "F.Fab")
			(effects
				(font
					(size 1.27 1.27)
				)
			)
		)
		(duplicate_pad_numbers_are_jumpers no)
		(fp_line
			(start -1.7272 -2.489962)
			(end -0.779018 -2.489962)
			(stroke
				(width 0.1524)
				(type default)
			)
			(layer "F.SilkS")
		)
		(fp_line
			(start -1.7272 2.489962)
			(end -1.7272 -2.489962)
			(stroke
				(width 0.1524)
				(type default)
			)
			(layer "F.SilkS")
		)
		(fp_line
			(start -0.779018 -2.489962)
			(end 0 -1.710944)
			(stroke
				(width 0.1524)
				(type default)
			)
			(layer "F.SilkS")
		)
		(fp_line
			(start 0 -1.710944)
			(end 0.779018 -2.489962)
			(stroke
				(width 0.1524)
				(type default)
			)
			(layer "F.SilkS")
		)
		(fp_line
			(start 0.779018 -2.489962)
			(end 1.7272 -2.489962)
			(stroke
				(width 0.1524)
				(type default)
			)
			(layer "F.SilkS")
		)
		(fp_line
			(start 1.7272 -2.489962)
			(end 1.7272 2.489962)
			(stroke
				(width 0.1524)
				(type default)
			)
			(layer "F.SilkS")
		)
		(fp_line
			(start 1.7272 2.489962)
			(end -1.7272 2.489962)
			(stroke
				(width 0.1524)
				(type default)
			)
			(layer "F.SilkS")
		)
		(fp_poly
			(pts
				(xy -3.821176 -2.2225) (xy -4.837176 -1.7145) (xy -4.837176 -2.7305)
			)
			(stroke
				(width 0)
				(type default)
			)
			(fill yes)
			(layer "F.SilkS")
		)
		(fp_line
			(start -1.994916 -2.489962)
			(end 1.994916 -2.489962)
			(stroke
				(width 0.1)
				(type default)
			)
			(layer "F.Fab")
		)
		(fp_line
			(start -1.994916 2.489962)
			(end -1.994916 -2.489962)
			(stroke
				(width 0.1)
				(type default)
			)
			(layer "F.Fab")
		)
		(fp_line
			(start 1.994916 -2.489962)
			(end 1.994916 2.489962)
			(stroke
				(width 0.1)
				(type default)
			)
			(layer "F.Fab")
		)
		(fp_line
			(start 1.994916 2.489962)
			(end -1.994916 2.489962)
			(stroke
				(width 0.1)
				(type default)
			)
			(layer "F.Fab")
		)
		(fp_poly
			(pts
				(xy -4.837176 -2.7305) (xy -4.837176 -1.7145) (xy -3.821176 -2.2225)
			)
			(stroke
				(width 0)
				(type default)
			)
			(fill yes)
			(layer "F.Fab")
		)
		(pad "1" smd rect
			(at -2.6924 -2.2225 270)
			(size 0.4318 1.6764)
			(layers "F.Cu" "F.Mask" "F.Paste")
			(net "FM_SPD_REMOTE_EN")
		)
		(pad "2" smd rect
			(at -2.6924 -1.5875 270)
			(size 0.4318 1.6764)
			(layers "F.Cu" "F.Mask" "F.Paste")
			(net "I3C_SPD_DDRABCD_CPU1_R_SCL")
		)
		(pad "3" smd rect
			(at -2.6924 -0.9525 270)
			(size 0.4318 1.6764)
			(layers "F.Cu" "F.Mask" "F.Paste")
			(net "I3C_SPD_DDRABCD_CPU1_BMC_SCL")
		)
		(pad "4" smd rect
			(at -2.6924 -0.3175 270)
			(size 0.4318 1.6764)
			(layers "F.Cu" "F.Mask" "F.Paste")
			(net "I3C_SPD_DDRABCD_CPU1_LVC1_R_SCL")
		)
		(pad "5" smd rect
			(at -2.6924 0.3175 270)
			(size 0.4318 1.6764)
			(layers "F.Cu" "F.Mask" "F.Paste")
			(net "I3C_SPD_DDRABCD_CPU1_R_SDA")
		)
		(pad "6" smd rect
			(at -2.6924 0.9525 270)
			(size 0.4318 1.6764)
			(layers "F.Cu" "F.Mask" "F.Paste")
			(net "I3C_SPD_DDRABCD_CPU1_BMC_SDA")
		)
		(pad "7" smd rect
			(at -2.6924 1.5875 270)
			(size 0.4318 1.6764)
			(layers "F.Cu" "F.Mask" "F.Paste")
			(net "I3C_SPD_DDRABCD_CPU1_LVC1_R_SDA")
		)
		(pad "8" smd rect
			(at -2.6924 2.2225 270)
			(size 0.4318 1.6764)
			(layers "F.Cu" "F.Mask" "F.Paste")
			(net "GND")
		)
		(pad "9" smd rect
			(at 2.6924 2.2225 270)
			(size 0.4318 1.6764)
			(layers "F.Cu" "F.Mask" "F.Paste")
			(net "I3C_SPD_DDREFGH_CPU1_LVC1_R_SCL")
		)
		(pad "10" smd rect
			(at 2.6924 1.5875 270)
			(size 0.4318 1.6764)
			(layers "F.Cu" "F.Mask" "F.Paste")
			(net "I3C_SPD_DDREFGH_CPU1_BMC_SCL")
		)
		(pad "11" smd rect
			(at 2.6924 0.9525 270)
			(size 0.4318 1.6764)
			(layers "F.Cu" "F.Mask" "F.Paste")
			(net "I3C_SPD_DDREFGH_CPU1_R_SCL")
		)
		(pad "12" smd rect
			(at 2.6924 0.3175 270)
			(size 0.4318 1.6764)
			(layers "F.Cu" "F.Mask" "F.Paste")
			(net "I3C_SPD_DDREFGH_CPU1_LVC1_R_SDA")
		)
		(pad "13" smd rect
			(at 2.6924 -0.3175 270)
			(size 0.4318 1.6764)
			(layers "F.Cu" "F.Mask" "F.Paste")
			(net "I3C_SPD_DDREFGH_CPU1_BMC_SDA")
		)
		(pad "14" smd rect
			(at 2.6924 -0.9525 270)
			(size 0.4318 1.6764)
			(layers "F.Cu" "F.Mask" "F.Paste")
			(net "I3C_SPD_DDREFGH_CPU1_R_SDA")
		)
		(pad "15" smd rect
			(at 2.6924 -1.5875 270)
			(size 0.4318 1.6764)
			(layers "F.Cu" "F.Mask" "F.Paste")
			(net "PD_I3C_SPD_DDR_CPU1_OE_N")
		)
		(pad "16" smd rect
			(at 2.6924 -2.2225 270)
			(size 0.4318 1.6764)
			(layers "F.Cu" "F.Mask" "F.Paste")
			(net "P3V3_AUX")
		)
	)
)
